(kicad_pcb
	(version 20260206)
	(generator "pcbnew")
	(generator_version "10.0")
	(general
		(thickness 1.6)
		(legacy_teardrops no)
	)
	(paper "A4")
	(title_block
		(title "01162023_DA0F0TEBIF0_F0T_Expander_BD_F_brd_V02_OCP.brd")
		(comment 1 "Grand Teton / footprints 4760-4764 of 9728")
	)
	(layers
		(0 "F.Cu" signal "TOP")
		(4 "In1.Cu" signal "GND")
		(6 "In2.Cu" signal "VCC")
		(8 "In3.Cu" signal "VCC1")
		(10 "In4.Cu" signal "GND1")
		(12 "In5.Cu" signal "IN1")
		(14 "In6.Cu" signal "GND2")
		(16 "In7.Cu" signal "IN2")
		(18 "In8.Cu" signal "GND3")
		(20 "In9.Cu" signal "IN3")
		(22 "In10.Cu" signal "GND4")
		(24 "In11.Cu" signal "IN4")
		(26 "In12.Cu" signal "GND5")
		(28 "In13.Cu" signal "IN5")
		(30 "In14.Cu" signal "GND6")
		(32 "In15.Cu" signal "IN6")
		(34 "In16.Cu" signal "GND7")
		(2 "B.Cu" signal "BOTTOM")
		(9 "F.Adhes" user "F.Adhesive")
		(11 "B.Adhes" user "B.Adhesive")
		(13 "F.Paste" user "Package Geometry/Pastemask Top")
		(15 "B.Paste" user "Package Geometry/Pastemask Bottom")
		(5 "F.SilkS" user "Ref Des/Silkscreen Top")
		(7 "B.SilkS" user "Ref Des/Silkscreen Bottom")
		(1 "F.Mask" user "Board Geometry/Soldermask Top")
		(3 "B.Mask" user "Board Geometry/Soldermask Bottom")
		(17 "Dwgs.User" user "User.Drawings")
		(19 "Cmts.User" user "User.Comments")
		(21 "Eco1.User" user "User.Eco1")
		(23 "Eco2.User" user "User.Eco2")
		(25 "Edge.Cuts" user "Board Geometry/Outline")
		(27 "Margin" user)
		(31 "F.CrtYd" user "Package Geometry/Place Bound Top")
		(29 "B.CrtYd" user "Package Geometry/Place Bound Bottom")
		(35 "F.Fab" user "Ref Des/Assembly Top")
		(33 "B.Fab" user "Ref Des/Assembly Bottom")
	)
	(footprint ""
		(layer "F.Cu")
		(at 214.497158 -82.135472)
		(property "Reference" "U330"
			(at -2.2606 -4.663948 0)
			(unlocked yes)
			(layer "F.SilkS")
			(effects
				(font
					(size 0.7874 0.5842)
					(thickness 0.1524)
				)
				(justify left)
			)
		)
		(property "Value" ""
			(at 0 0 0)
			(layer "F.Fab")
			(effects
				(font
					(size 1.27 1.27)
				)
			)
		)
		(duplicate_pad_numbers_are_jumpers no)
		(fp_line
			(start -2.097532 -3.949954)
			(end -2.097532 3.949954)
			(stroke
				(width 0.1524)
				(type default)
			)
			(layer "F.SilkS")
		)
		(fp_line
			(start -2.097532 3.949954)
			(end 2.097532 3.949954)
			(stroke
				(width 0.1524)
				(type default)
			)
			(layer "F.SilkS")
		)
		(fp_line
			(start -1.409954 -3.949954)
			(end -2.097532 -3.949954)
			(stroke
				(width 0.1524)
				(type default)
			)
			(layer "F.SilkS")
		)
		(fp_line
			(start 0 -2.54)
			(end -1.409954 -3.949954)
			(stroke
				(width 0.1524)
				(type default)
			)
			(layer "F.SilkS")
		)
		(fp_line
			(start 1.409954 -3.949954)
			(end 0 -2.54)
			(stroke
				(width 0.1524)
				(type default)
			)
			(layer "F.SilkS")
		)
		(fp_line
			(start 2.097532 -3.949954)
			(end 1.409954 -3.949954)
			(stroke
				(width 0.1524)
				(type default)
			)
			(layer "F.SilkS")
		)
		(fp_line
			(start 2.097532 3.949954)
			(end 2.097532 -3.949954)
			(stroke
				(width 0.1524)
				(type default)
			)
			(layer "F.SilkS")
		)
		(fp_poly
			(pts
				(xy -4.7498 -4.182872) (xy -4.7498 -3.166872) (xy -3.7338 -3.674872)
			)
			(stroke
				(width 0)
				(type default)
			)
			(fill yes)
			(layer "F.SilkS")
		)
		(fp_line
			(start -2.249932 -3.949954)
			(end -2.249932 3.949954)
			(stroke
				(width 0.1)
				(type default)
			)
			(layer "F.Fab")
		)
		(fp_line
			(start -2.249932 3.949954)
			(end 2.249932 3.949954)
			(stroke
				(width 0.1)
				(type default)
			)
			(layer "F.Fab")
		)
		(fp_line
			(start 2.249932 -3.949954)
			(end -2.249932 -3.949954)
			(stroke
				(width 0.1)
				(type default)
			)
			(layer "F.Fab")
		)
		(fp_line
			(start 2.249932 3.949954)
			(end 2.249932 -3.949954)
			(stroke
				(width 0.1)
				(type default)
			)
			(layer "F.Fab")
		)
		(fp_poly
			(pts
				(xy -4.7498 -4.182872) (xy -4.7498 -3.166872) (xy -3.7338 -3.674872)
			)
			(stroke
				(width 0)
				(type default)
			)
			(fill yes)
			(layer "F.Fab")
		)
		(pad "1" smd rect
			(at -2.925064 -3.674872 270)
			(size 0.6096 1.3716)
			(layers "F.Cu" "F.Mask" "F.Paste")
			(net "IRQ_SSD_LED_IOEXP_N")
		)
		(pad "2" smd rect
			(at -2.925064 -2.925064 270)
			(size 0.4064 1.3716)
			(layers "F.Cu" "F.Mask" "F.Paste")
			(net "SSD_LED_IOEXP_A1")
		)
		(pad "3" smd rect
			(at -2.925064 -2.275078 270)
			(size 0.4064 1.3716)
			(layers "F.Cu" "F.Mask" "F.Paste")
			(net "RST_SSD_LED_IOEXP_R_N")
		)
		(pad "4" smd rect
			(at -2.925064 -1.625092 270)
			(size 0.4064 1.3716)
			(layers "F.Cu" "F.Mask" "F.Paste")
			(net "SSD0_LED")
		)
		(pad "5" smd rect
			(at -2.925064 -0.975106 270)
			(size 0.4064 1.3716)
			(layers "F.Cu" "F.Mask" "F.Paste")
			(net "SSD1_LED")
		)
		(pad "6" smd rect
			(at -2.925064 -0.32512 270)
			(size 0.4064 1.3716)
			(layers "F.Cu" "F.Mask" "F.Paste")
			(net "SSD2_LED")
		)
		(pad "7" smd rect
			(at -2.925064 0.32512 270)
			(size 0.4064 1.3716)
			(layers "F.Cu" "F.Mask" "F.Paste")
			(net "SSD3_LED")
		)
		(pad "8" smd rect
			(at -2.925064 0.975106 270)
			(size 0.4064 1.3716)
			(layers "F.Cu" "F.Mask" "F.Paste")
			(net "SSD4_LED")
		)
		(pad "9" smd rect
			(at -2.925064 1.625092 270)
			(size 0.4064 1.3716)
			(layers "F.Cu" "F.Mask" "F.Paste")
			(net "SSD5_LED")
		)
		(pad "10" smd rect
			(at -2.925064 2.275078 270)
			(size 0.4064 1.3716)
			(layers "F.Cu" "F.Mask" "F.Paste")
			(net "SSD6_LED")
		)
		(pad "11" smd rect
			(at -2.925064 2.925064 270)
			(size 0.4064 1.3716)
			(layers "F.Cu" "F.Mask" "F.Paste")
			(net "SSD7_LED")
		)
		(pad "12" smd rect
			(at -2.925064 3.674872 270)
			(size 0.6096 1.3716)
			(layers "F.Cu" "F.Mask" "F.Paste")
			(net "GND")
		)
		(pad "13" smd rect
			(at 2.925064 3.674872 270)
			(size 0.6096 1.3716)
			(layers "F.Cu" "F.Mask" "F.Paste")
			(net "SSD8_LED")
		)
		(pad "14" smd rect
			(at 2.925064 2.925064 270)
			(size 0.4064 1.3716)
			(layers "F.Cu" "F.Mask" "F.Paste")
			(net "SSD9_LED")
		)
		(pad "15" smd rect
			(at 2.925064 2.275078 270)
			(size 0.4064 1.3716)
			(layers "F.Cu" "F.Mask" "F.Paste")
			(net "SSD10_LED")
		)
		(pad "16" smd rect
			(at 2.925064 1.625092 270)
			(size 0.4064 1.3716)
			(layers "F.Cu" "F.Mask" "F.Paste")
			(net "SSD11_LED")
		)
		(pad "17" smd rect
			(at 2.925064 0.975106 270)
			(size 0.4064 1.3716)
			(layers "F.Cu" "F.Mask" "F.Paste")
			(net "SSD12_LED")
		)
		(pad "18" smd rect
			(at 2.925064 0.32512 270)
			(size 0.4064 1.3716)
			(layers "F.Cu" "F.Mask" "F.Paste")
			(net "SSD13_LED")
		)
		(pad "19" smd rect
			(at 2.925064 -0.32512 270)
			(size 0.4064 1.3716)
			(layers "F.Cu" "F.Mask" "F.Paste")
			(net "SSD14_LED")
		)
		(pad "20" smd rect
			(at 2.925064 -0.975106 270)
			(size 0.4064 1.3716)
			(layers "F.Cu" "F.Mask" "F.Paste")
			(net "SSD15_LED")
		)
		(pad "21" smd rect
			(at 2.925064 -1.625092 270)
			(size 0.4064 1.3716)
			(layers "F.Cu" "F.Mask" "F.Paste")
			(net "SSD_LED_IOEXP_A0")
		)
		(pad "22" smd rect
			(at 2.925064 -2.275078 270)
			(size 0.4064 1.3716)
			(layers "F.Cu" "F.Mask" "F.Paste")
			(net "SMB_SSD_LED_IOEXP_SCL")
		)
		(pad "23" smd rect
			(at 2.925064 -2.925064 270)
			(size 0.4064 1.3716)
			(layers "F.Cu" "F.Mask" "F.Paste")
			(net "SMB_SSD_LED_IOEXP_SDA")
		)
		(pad "24" smd rect
			(at 2.925064 -3.674872 270)
			(size 0.6096 1.3716)
			(layers "F.Cu" "F.Mask" "F.Paste")
			(net "P3V3_AUX")
		)
	)
	(footprint ""
		(layer "F.Cu")
		(at 383.818384 -252.356874 -90)
		(property "Reference" "R1437"
			(at 0 0 270)
			(layer "F.SilkS")
			(hide yes)
			(effects
				(font
					(size 1.27 1.27)
				)
			)
		)
		(property "Value" ""
			(at 0 0 270)
			(layer "F.Fab")
			(effects
				(font
					(size 1.27 1.27)
				)
			)
		)
		(duplicate_pad_numbers_are_jumpers no)
		(fp_line
			(start -0.7874 0.4064)
			(end -0.7874 -0.4064)
			(stroke
				(width 0.1524)
				(type default)
			)
			(layer "F.SilkS")
		)
		(fp_line
			(start 0.7874 0.4064)
			(end -0.7874 0.4064)
			(stroke
				(width 0.1524)
				(type default)
			)
			(layer "F.SilkS")
		)
		(fp_line
			(start -0.7874 -0.4064)
			(end 0.7874 -0.4064)
			(stroke
				(width 0.1524)
				(type default)
			)
			(layer "F.SilkS")
		)
		(fp_line
			(start 0.7874 -0.4064)
			(end 0.7874 0.4064)
			(stroke
				(width 0.1524)
				(type default)
			)
			(layer "F.SilkS")
		)
		(fp_line
			(start -0.67945 0.3048)
			(end -0.67945 -0.305054)
			(stroke
				(width 0.1)
				(type default)
			)
			(layer "F.Fab")
		)
		(fp_line
			(start -0.12065 0.3048)
			(end -0.67945 0.3048)
			(stroke
				(width 0.1)
				(type default)
			)
			(layer "F.Fab")
		)
		(fp_line
			(start 0.120396 0.3048)
			(end 0.120396 0.2794)
			(stroke
				(width 0.1)
				(type default)
			)
			(layer "F.Fab")
		)
		(fp_line
			(start 0.67945 0.3048)
			(end 0.120396 0.3048)
			(stroke
				(width 0.1)
				(type default)
			)
			(layer "F.Fab")
		)
		(fp_line
			(start -0.12065 0.2794)
			(end -0.12065 0.3048)
			(stroke
				(width 0.1)
				(type default)
			)
			(layer "F.Fab")
		)
		(fp_line
			(start 0.120396 0.2794)
			(end -0.12065 0.2794)
			(stroke
				(width 0.1)
				(type default)
			)
			(layer "F.Fab")
		)
		(fp_line
			(start -0.12065 -0.2794)
			(end 0.12065 -0.2794)
			(stroke
				(width 0.1)
				(type default)
			)
			(layer "F.Fab")
		)
		(fp_line
			(start 0.12065 -0.2794)
			(end 0.12065 -0.3048)
			(stroke
				(width 0.1)
				(type default)
			)
			(layer "F.Fab")
		)
		(fp_line
			(start 0.12065 -0.3048)
			(end 0.67945 -0.3048)
			(stroke
				(width 0.1)
				(type default)
			)
			(layer "F.Fab")
		)
		(fp_line
			(start 0.67945 -0.3048)
			(end 0.67945 0.3048)
			(stroke
				(width 0.1)
				(type default)
			)
			(layer "F.Fab")
		)
		(fp_line
			(start -0.67945 -0.305054)
			(end -0.12065 -0.305054)
			(stroke
				(width 0.1)
				(type default)
			)
			(layer "F.Fab")
		)
		(fp_line
			(start -0.12065 -0.305054)
			(end -0.12065 -0.2794)
			(stroke
				(width 0.1)
				(type default)
			)
			(layer "F.Fab")
		)
		(pad "1" smd circle
			(at -0.40005 0 270)
			(size 0 0)
			(layers "F.Cu" "F.Mask" "F.Paste")
			(net "GND")
		)
		(pad "2" smd circle
			(at 0.40005 0 270)
			(size 0 0)
			(layers "F.Cu" "F.Mask" "F.Paste")
			(net "PEX3_MODE_SEL12")
		)
	)
	(footprint ""
		(layer "F.Cu")
		(at 400.543776 -47.92091)
		(property "Reference" "R647"
			(at 0 0 0)
			(layer "F.SilkS")
			(hide yes)
			(effects
				(font
					(size 1.27 1.27)
				)
			)
		)
		(property "Value" ""
			(at 0 0 0)
			(layer "F.Fab")
			(effects
				(font
					(size 1.27 1.27)
				)
			)
		)
		(duplicate_pad_numbers_are_jumpers no)
		(fp_line
			(start -0.7874 -0.4064)
			(end 0.7874 -0.4064)
			(stroke
				(width 0.1524)
				(type default)
			)
			(layer "F.SilkS")
		)
		(fp_line
			(start -0.7874 0.4064)
			(end -0.7874 -0.4064)
			(stroke
				(width 0.1524)
				(type default)
			)
			(layer "F.SilkS")
		)
		(fp_line
			(start 0.7874 -0.4064)
			(end 0.7874 0.4064)
			(stroke
				(width 0.1524)
				(type default)
			)
			(layer "F.SilkS")
		)
		(fp_line
			(start 0.7874 0.4064)
			(end -0.7874 0.4064)
			(stroke
				(width 0.1524)
				(type default)
			)
			(layer "F.SilkS")
		)
		(fp_line
			(start -0.67945 -0.305054)
			(end -0.12065 -0.305054)
			(stroke
				(width 0.1)
				(type default)
			)
			(layer "F.Fab")
		)
		(fp_line
			(start -0.67945 0.3048)
			(end -0.67945 -0.305054)
			(stroke
				(width 0.1)
				(type default)
			)
			(layer "F.Fab")
		)
		(fp_line
			(start -0.12065 -0.305054)
			(end -0.12065 -0.2794)
			(stroke
				(width 0.1)
				(type default)
			)
			(layer "F.Fab")
		)
		(fp_line
			(start -0.12065 -0.2794)
			(end 0.12065 -0.2794)
			(stroke
				(width 0.1)
				(type default)
			)
			(layer "F.Fab")
		)
		(fp_line
			(start -0.12065 0.2794)
			(end -0.12065 0.3048)
			(stroke
				(width 0.1)
				(type default)
			)
			(layer "F.Fab")
		)
		(fp_line
			(start -0.12065 0.3048)
			(end -0.67945 0.3048)
			(stroke
				(width 0.1)
				(type default)
			)
			(layer "F.Fab")
		)
		(fp_line
			(start 0.120396 0.2794)
			(end -0.12065 0.2794)
			(stroke
				(width 0.1)
				(type default)
			)
			(layer "F.Fab")
		)
		(fp_line
			(start 0.120396 0.3048)
			(end 0.120396 0.2794)
			(stroke
				(width 0.1)
				(type default)
			)
			(layer "F.Fab")
		)
		(fp_line
			(start 0.12065 -0.3048)
			(end 0.67945 -0.3048)
			(stroke
				(width 0.1)
				(type default)
			)
			(layer "F.Fab")
		)
		(fp_line
			(start 0.12065 -0.2794)
			(end 0.12065 -0.3048)
			(stroke
				(width 0.1)
				(type default)
			)
			(layer "F.Fab")
		)
		(fp_line
			(start 0.67945 -0.3048)
			(end 0.67945 0.3048)
			(stroke
				(width 0.1)
				(type default)
			)
			(layer "F.Fab")
		)
		(fp_line
			(start 0.67945 0.3048)
			(end 0.120396 0.3048)
			(stroke
				(width 0.1)
				(type default)
			)
			(layer "F.Fab")
		)
		(pad "1" smd circle
			(at -0.40005 0)
			(size 0 0)
			(layers "F.Cu" "F.Mask" "F.Paste")
			(net "P3V3_AUX")
		)
		(pad "2" smd circle
			(at 0.40005 0)
			(size 0 0)
			(layers "F.Cu" "F.Mask" "F.Paste")
			(net "SSD_8_15_ADC_ALERT_N")
		)
	)
	(footprint ""
		(layer "F.Cu")
		(at 135.325612 -159.082994 -90)
		(property "Reference" "PD81"
			(at 4.295394 -2.750058 90)
			(unlocked yes)
			(layer "F.SilkS")
			(effects
				(font
					(size 0.7874 0.5842)
					(thickness 0.1524)
				)
				(justify left)
			)
		)
		(property "Value" ""
			(at 0 0 270)
			(layer "F.Fab")
			(effects
				(font
					(size 1.27 1.27)
				)
			)
		)
		(duplicate_pad_numbers_are_jumpers no)
		(fp_line
			(start -3.656584 1.970024)
			(end 4.240784 1.970024)
			(stroke
				(width 0.1524)
				(type default)
			)
			(layer "F.SilkS")
		)
		(fp_line
			(start 4.240784 1.970024)
			(end 4.240784 -1.970024)
			(stroke
				(width 0.1524)
				(type default)
			)
			(layer "F.SilkS")
		)
		(fp_line
			(start -3.656584 -1.970024)
			(end -3.656584 1.970024)
			(stroke
				(width 0.1524)
				(type default)
			)
			(layer "F.SilkS")
		)
		(fp_line
			(start 4.240784 -1.970024)
			(end -3.656584 -1.970024)
			(stroke
				(width 0.1524)
				(type default)
			)
			(layer "F.SilkS")
		)
		(fp_poly
			(pts
				(xy 3.580384 1.970024) (xy 3.580384 -1.970024) (xy 4.240784 -1.970024) (xy 4.240784 1.970024)
			)
			(stroke
				(width 0)
				(type default)
			)
			(fill yes)
			(layer "F.SilkS")
		)
		(fp_line
			(start -2.3749 1.970024)
			(end 2.3749 1.970024)
			(stroke
				(width 0.1)
				(type default)
			)
			(layer "F.Fab")
		)
		(fp_line
			(start 2.3749 1.970024)
			(end 2.3749 -1.970024)
			(stroke
				(width 0.1)
				(type default)
			)
			(layer "F.Fab")
		)
		(fp_line
			(start -2.3749 -1.970024)
			(end -2.3749 1.970024)
			(stroke
				(width 0.1)
				(type default)
			)
			(layer "F.Fab")
		)
		(fp_line
			(start 2.3749 -1.970024)
			(end -2.3749 -1.970024)
			(stroke
				(width 0.1)
				(type default)
			)
			(layer "F.Fab")
		)
		(fp_text user "+"
			(at -4.9784 -0.23495 270)
			(unlocked yes)
			(layer "F.Fab")
			(effects
				(font
					(size 1.905 1.4224)
					(thickness 0.1524)
				)
				(justify left)
			)
		)
		(fp_text user "-"
			(at 4.1656 -0.23495 270)
			(unlocked yes)
			(layer "F.Fab")
			(effects
				(font
					(size 1.905 1.4224)
					(thickness 0.1524)
				)
				(justify left)
			)
		)
		(pad "A" smd rect
			(at -2.450084 0 270)
			(size 2.159 2.2606)
			(layers "F.Cu" "F.Mask" "F.Paste")
			(net "GND")
		)
		(pad "C" smd rect
			(at 2.450084 0 270)
			(size 2.159 2.2606)
			(layers "F.Cu" "F.Mask" "F.Paste")
			(net "P12V_AUX")
		)
	)
	(footprint ""
		(layer "F.Cu")
		(at 259.130038 -281.203908 -90)
		(property "Reference" "C3383"
			(at 0 0 270)
			(layer "F.SilkS")
			(hide yes)
			(effects
				(font
					(size 1.27 1.27)
				)
			)
		)
		(property "Value" ""
			(at 0 0 270)
			(layer "F.Fab")
			(effects
				(font
					(size 1.27 1.27)
				)
			)
		)
		(duplicate_pad_numbers_are_jumpers no)
		(fp_line
			(start -1.2954 0.5842)
			(end -1.2954 -0.5842)
			(stroke
				(width 0.1524)
				(type default)
			)
			(layer "F.SilkS")
		)
		(fp_line
			(start 1.2954 0.5842)
			(end -1.2954 0.5842)
			(stroke
				(width 0.1524)
				(type default)
			)
			(layer "F.SilkS")
		)
		(fp_line
			(start -1.2954 -0.5842)
			(end 1.2954 -0.5842)
			(stroke
				(width 0.1524)
				(type default)
			)
			(layer "F.SilkS")
		)
		(fp_line
			(start 1.2954 -0.5842)
			(end 1.2954 0.5842)
			(stroke
				(width 0.1524)
				(type default)
			)
			(layer "F.SilkS")
		)
		(fp_line
			(start -0.8636 0.4572)
			(end -0.8636 0.4064)
			(stroke
				(width 0.1)
				(type default)
			)
			(layer "F.Fab")
		)
		(fp_line
			(start 0.8636 0.4572)
			(end -0.8636 0.4572)
			(stroke
				(width 0.1)
				(type default)
			)
			(layer "F.Fab")
		)
		(fp_line
			(start -1.1938 0.4064)
			(end -1.1938 -0.4064)
			(stroke
				(width 0.1)
				(type default)
			)
			(layer "F.Fab")
		)
		(fp_line
			(start -0.8636 0.4064)
			(end -1.1938 0.4064)
			(stroke
				(width 0.1)
				(type default)
			)
			(layer "F.Fab")
		)
		(fp_line
			(start 0.8636 0.4064)
			(end 0.8636 0.4572)
			(stroke
				(width 0.1)
				(type default)
			)
			(layer "F.Fab")
		)
		(fp_line
			(start 1.1938 0.4064)
			(end 0.8636 0.4064)
			(stroke
				(width 0.1)
				(type default)
			)
			(layer "F.Fab")
		)
		(fp_line
			(start -1.1938 -0.4064)
			(end -0.8636 -0.4064)
			(stroke
				(width 0.1)
				(type default)
			)
			(layer "F.Fab")
		)
		(fp_line
			(start -0.8636 -0.4064)
			(end -0.8636 -0.4572)
			(stroke
				(width 0.1)
				(type default)
			)
			(layer "F.Fab")
		)
		(fp_line
			(start 0.8636 -0.4064)
			(end 1.1938 -0.4064)
			(stroke
				(width 0.1)
				(type default)
			)
			(layer "F.Fab")
		)
		(fp_line
			(start 1.1938 -0.4064)
			(end 1.1938 0.4064)
			(stroke
				(width 0.1)
				(type default)
			)
			(layer "F.Fab")
		)
		(fp_line
			(start -0.8636 -0.4572)
			(end 0.8636 -0.4572)
			(stroke
				(width 0.1)
				(type default)
			)
			(layer "F.Fab")
		)
		(fp_line
			(start 0.8636 -0.4572)
			(end 0.8636 -0.4064)
			(stroke
				(width 0.1)
				(type default)
			)
			(layer "F.Fab")
		)
		(pad "1" smd rect
			(at -0.7366 0 180)
			(size 0.7112 0.8128)
			(layers "F.Cu" "F.Mask" "F.Paste")
			(net "P1V8_PLL0_PEX2")
		)
		(pad "2" smd rect
			(at 0.7366 0 180)
			(size 0.7112 0.8128)
			(layers "F.Cu" "F.Mask" "F.Paste")
			(net "GND")
		)
	)
)
